FILE_TYPE = CONNECTIVITY;
{Allegro Design Entry HDL 16.6-p007 (v16-6-112F) 10/10/2012}
"PAGE_NUMBER" = 243;
0"NC";
1"GND\g";
2"GND\g";
3"PVDDQ_GHJ\g";
4"GND\g";
5"PVDDQ_KLM\g";
6"PVDDQ_GHJ\g";
7"GND\g";
8"PVDDQ_KLM\g";
9"GND\g";
10"PVDDQ_KLM\g";
11"GND\g";
12"PVDDQ_GHJ\g";
%"GND"
"1","(-7750,1450)","0","mstr_symbols","I1";
;
CDS_LIB"mstr_symbols"
SIZE"1B"
BOM_COST"PROC_VRD_VCCIN_CPU0"
ROOM"VDDQ_ABC_PWR_VR"
VOLTAGE"0"
BODY_TYPE"PLUMBING"
HDL_POWER"GND";
"A\NAC"1;
%"GND"
"1","(-7750,3350)","0","mstr_symbols","I11";
;
VOLTAGE"0"
ROOM"VDDQ_ABC_PWR_VR"
BOM_COST"PROC_VRD_VCCIN_CPU0"
SIZE"1B"
CDS_LIB"mstr_symbols"
BODY_TYPE"PLUMBING"
HDL_POWER"GND";
"A\NAC"2;
%"PVDDQ_GHJ"
"1","(-7750,4050)","0","mstr_symbols","I26";
;
HDL_POWER"PVDDQ_GHJ"
BODY_TYPE"PLUMBING"
CDS_LIB"mstr_symbols"
VOLTAGE"1.2V";
"G\NAC"3;
%"GND"
"1","(-3800,1450)","0","mstr_symbols","I27";
;
HDL_POWER"GND"
BODY_TYPE"PLUMBING"
CDS_LIB"mstr_symbols"
VOLTAGE"0"
ROOM"VDDQ_ABC_PWR_VR"
BOM_COST"PROC_VRD_VCCIN_CPU0"
SIZE"1B";
"A\NAC"4;
%"PVDDQ_KLM"
"1","(-3800,2150)","0","mstr_symbols","I29";
;
HDL_POWER"PVDDQ_KLM"
BODY_TYPE"PLUMBING"
CDS_LIB"mstr_symbols"
BOM_COST"VDDQ_KLM_PWR_VR"
ROOM"VDDQ_KLM_PWR_VR"
VOLTAGE"1.2V";
"G\NAC"5;
%"PVDDQ_GHJ"
"1","(-7750,2150)","0","mstr_symbols","I3";
;
CDS_LIB"mstr_symbols"
VOLTAGE"1.2V"
BODY_TYPE"PLUMBING"
HDL_POWER"PVDDQ_GHJ";
"G\NAC"6;
%"GND"
"1","(-3800,2400)","0","mstr_symbols","I34";
;
VOLTAGE"0"
ROOM"VDDQ_ABC_PWR_VR"
BOM_COST"PROC_VRD_VCCIN_CPU0"
SIZE"1B"
CDS_LIB"mstr_symbols"
BODY_TYPE"PLUMBING"
HDL_POWER"GND";
"A\NAC"7;
%"PVDDQ_KLM"
"1","(-3800,3100)","0","mstr_symbols","I36";
;
VOLTAGE"1.2V"
ROOM"VDDQ_KLM_PWR_VR"
BOM_COST"VDDQ_KLM_PWR_VR"
CDS_LIB"mstr_symbols"
BODY_TYPE"PLUMBING"
HDL_POWER"PVDDQ_KLM";
"G\NAC"8;
%"GND"
"1","(-3800,3350)","0","mstr_symbols","I38";
;
HDL_POWER"GND"
BODY_TYPE"PLUMBING"
CDS_LIB"mstr_symbols"
SIZE"1B"
BOM_COST"PROC_VRD_VCCIN_CPU0"
ROOM"VDDQ_ABC_PWR_VR"
VOLTAGE"0";
"A\NAC"9;
%"PVDDQ_KLM"
"1","(-3800,4050)","0","mstr_symbols","I51";
;
HDL_POWER"PVDDQ_KLM"
BODY_TYPE"PLUMBING"
CDS_LIB"mstr_symbols"
BOM_COST"VDDQ_KLM_PWR_VR"
ROOM"VDDQ_KLM_PWR_VR"
VOLTAGE"1.2V";
"G\NAC"10;
%"CAP_A"
"1","(-7750,2800)","0","dev_discrete","I53";
;
CDS_SEC"1"
CDS_LOCATION"C5G79"
MATERIAL"X6S"
LOCATION"C5G79"
VALUE"22.0UF"
VOLTAGE"4V"
TOLERANCE"20%"
PACK_TYPE"0603V"
PART_NUMBER"E15431-004"
GROUP"PWR_MLCC_CAP"
BOM_DS"NOPOP"
CDS_LIB"dev_discrete"
ROOM"PVDDQ_KLM"
SEC"1"
SEC_TYPE"0603V";
"B"
$PN"2"11;
"A"
$PN"1"12;
%"CAP_A"
"1","(-4550,2775)","0","dev_discrete","I54";
;
CDS_SEC"1"
CDS_LOCATION"C5G87"
MATERIAL"X6S"
TOLERANCE"20%"
PACK_TYPE"0603V"
LOCATION"C5G87"
VOLTAGE"4V"
VALUE"22.0UF"
PART_NUMBER"E15431-004"
GROUP"PWR_MLCC_CAP"
BOM_DS"NOPOP"
CDS_LIB"dev_discrete"
ROOM"PVDDQ_KLM"
SEC"1"
SEC_TYPE"0603V";
"B"
$PN"2"11;
"A"
$PN"1"12;
%"CAP_A"
"1","(-4950,2800)","0","dev_discrete","I55";
;
CDS_SEC"1"
CDS_LOCATION"C5G86"
MATERIAL"X6S"
LOCATION"C5G86"
PACK_TYPE"0603V"
VOLTAGE"4V"
TOLERANCE"20%"
VALUE"22.0UF"
GROUP"PWR_MLCC_CAP"
PART_NUMBER"E15431-004"
BOM_DS"NOPOP"
CDS_LIB"dev_discrete"
ROOM"PVDDQ_KLM"
SEC"1"
SEC_TYPE"0603V";
"B"
$PN"2"11;
"A"
$PN"1"12;
%"CAP_A"
"1","(-5350,2800)","0","dev_discrete","I56";
;
CDS_SEC"1"
CDS_LOCATION"C5G85"
VALUE"22.0UF"
VOLTAGE"4V"
PACK_TYPE"0603V"
TOLERANCE"20%"
LOCATION"C5G85"
GROUP"PWR_MLCC_CAP"
MATERIAL"X6S"
PART_NUMBER"E15431-004"
BOM_DS"NOPOP"
CDS_LIB"dev_discrete"
ROOM"PVDDQ_KLM"
SEC"1"
SEC_TYPE"0603V";
"B"
$PN"2"11;
"A"
$PN"1"12;
%"CAP_A"
"1","(-5750,2800)","0","dev_discrete","I57";
;
CDS_SEC"1"
CDS_LOCATION"C5G84"
LOCATION"C5G84"
VALUE"22.0UF"
PACK_TYPE"0603V"
VOLTAGE"4V"
TOLERANCE"20%"
GROUP"PWR_MLCC_CAP"
MATERIAL"X6S"
PART_NUMBER"E15431-004"
BOM_DS"NOPOP"
CDS_LIB"dev_discrete"
ROOM"PVDDQ_KLM"
SEC"1"
SEC_TYPE"0603V";
"B"
$PN"2"11;
"A"
$PN"1"12;
%"CAP_A"
"1","(-6150,2800)","0","dev_discrete","I58";
;
CDS_SEC"1"
CDS_LOCATION"C5G83"
MATERIAL"X6S"
PACK_TYPE"0603V"
PART_NUMBER"E15431-004"
TOLERANCE"20%"
LOCATION"C5G83"
GROUP"PWR_MLCC_CAP"
VOLTAGE"4V"
VALUE"22.0UF"
BOM_DS"NOPOP"
CDS_LIB"dev_discrete"
ROOM"PVDDQ_KLM"
SEC"1"
SEC_TYPE"0603V";
"B"
$PN"2"11;
"A"
$PN"1"12;
%"CAP_A"
"1","(-6550,2800)","0","dev_discrete","I59";
;
CDS_SEC"1"
CDS_LOCATION"C5G82"
MATERIAL"X6S"
LOCATION"C5G82"
VALUE"22.0UF"
VOLTAGE"4V"
TOLERANCE"20%"
PACK_TYPE"0603V"
GROUP"PWR_MLCC_CAP"
PART_NUMBER"E15431-004"
BOM_DS"NOPOP"
CDS_LIB"dev_discrete"
ROOM"PVDDQ_KLM"
SEC"1"
SEC_TYPE"0603V";
"B"
$PN"2"11;
"A"
$PN"1"12;
%"GND"
"1","(-7750,2400)","0","mstr_symbols","I6";
;
HDL_POWER"GND"
BODY_TYPE"PLUMBING"
CDS_LIB"mstr_symbols"
SIZE"1B"
BOM_COST"PROC_VRD_VCCIN_CPU0"
ROOM"VDDQ_ABC_PWR_VR"
VOLTAGE"0";
"A\NAC"11;
%"CAP_A"
"1","(-6950,2800)","0","dev_discrete","I60";
;
CDS_SEC"1"
CDS_LOCATION"C5G81"
PACK_TYPE"0603V"
PART_NUMBER"E15431-004"
MATERIAL"X6S"
LOCATION"C5G81"
VALUE"22.0UF"
TOLERANCE"20%"
VOLTAGE"4V"
GROUP"PWR_MLCC_CAP"
BOM_DS"NOPOP"
CDS_LIB"dev_discrete"
ROOM"PVDDQ_KLM"
SEC"1"
SEC_TYPE"0603V";
"B"
$PN"2"11;
"A"
$PN"1"12;
%"CAP_A"
"1","(-7350,2800)","0","dev_discrete","I61";
;
CDS_SEC"1"
CDS_LOCATION"C5G80"
LOCATION"C5G80"
MATERIAL"X6S"
VALUE"22.0UF"
PACK_TYPE"0603V"
VOLTAGE"4V"
TOLERANCE"20%"
PART_NUMBER"E15431-004"
GROUP"PWR_MLCC_CAP"
BOM_DS"NOPOP"
CDS_LIB"dev_discrete"
ROOM"PVDDQ_KLM"
SEC"1"
SEC_TYPE"0603V";
"B"
$PN"2"11;
"A"
$PN"1"12;
%"CAP_A"
"1","(-4550,1850)","0","dev_discrete","I62";
;
CDS_SEC"1"
CDS_LOCATION"C5G96"
BOM_DS"NOPOP"
GROUP"PWR_MLCC_CAP"
PACK_TYPE"0603V"
PART_NUMBER"E15431-004"
MATERIAL"X6S"
VOLTAGE"4V"
TOLERANCE"20%"
VALUE"22.0UF"
LOCATION"C5G96"
SEC_TYPE"0603V"
SEC"1"
CDS_LIB"dev_discrete"
ROOM"PVDDQ_KLM";
"B"
$PN"2"1;
"A"
$PN"1"6;
%"CAP_A"
"1","(-4950,1850)","0","dev_discrete","I63";
;
CDS_SEC"1"
CDS_LOCATION"C5G95"
BOM_DS"NOPOP"
GROUP"PWR_MLCC_CAP"
PART_NUMBER"E15431-004"
TOLERANCE"20%"
MATERIAL"X6S"
VOLTAGE"4V"
LOCATION"C5G95"
PACK_TYPE"0603V"
VALUE"22.0UF"
ROOM"PVDDQ_KLM"
CDS_LIB"dev_discrete"
SEC"1"
SEC_TYPE"0603V";
"B"
$PN"2"1;
"A"
$PN"1"6;
%"CAP_A"
"1","(-5350,1850)","0","dev_discrete","I64";
;
CDS_SEC"1"
CDS_LOCATION"C5G94"
VALUE"22.0UF"
LOCATION"C5G94"
TOLERANCE"20%"
VOLTAGE"4V"
PACK_TYPE"0603V"
PART_NUMBER"E15431-004"
MATERIAL"X6S"
GROUP"PWR_MLCC_CAP"
BOM_DS"NOPOP"
SEC_TYPE"0603V"
SEC"1"
CDS_LIB"dev_discrete"
ROOM"PVDDQ_KLM";
"B"
$PN"2"1;
"A"
$PN"1"6;
%"CAP_A"
"1","(-5750,1850)","0","dev_discrete","I65";
;
CDS_SEC"1"
CDS_LOCATION"C5G93"
TOLERANCE"20%"
PACK_TYPE"0603V"
LOCATION"C5G93"
VALUE"22.0UF"
VOLTAGE"4V"
PART_NUMBER"E15431-004"
MATERIAL"X6S"
GROUP"PWR_MLCC_CAP"
BOM_DS"NOPOP"
SEC_TYPE"0603V"
SEC"1"
CDS_LIB"dev_discrete"
ROOM"PVDDQ_KLM";
"B"
$PN"2"1;
"A"
$PN"1"6;
%"CAP_A"
"1","(-6150,1850)","0","dev_discrete","I66";
;
CDS_SEC"1"
CDS_LOCATION"C5G92"
PACK_TYPE"0603V"
LOCATION"C5G92"
VALUE"22.0UF"
VOLTAGE"4V"
TOLERANCE"20%"
PART_NUMBER"E15431-004"
MATERIAL"X6S"
GROUP"PWR_MLCC_CAP"
BOM_DS"NOPOP"
SEC_TYPE"0603V"
SEC"1"
CDS_LIB"dev_discrete"
ROOM"PVDDQ_KLM";
"B"
$PN"2"1;
"A"
$PN"1"6;
%"CAP_A"
"1","(-6550,1850)","0","dev_discrete","I67";
;
CDS_SEC"1"
CDS_LOCATION"C5G91"
PACK_TYPE"0603V"
MATERIAL"X6S"
LOCATION"C5G91"
VALUE"22.0UF"
VOLTAGE"4V"
TOLERANCE"20%"
PART_NUMBER"E15431-004"
GROUP"PWR_MLCC_CAP"
BOM_DS"NOPOP"
SEC_TYPE"0603V"
SEC"1"
ROOM"PVDDQ_KLM"
CDS_LIB"dev_discrete";
"B"
$PN"2"1;
"A"
$PN"1"6;
%"CAP_A"
"1","(-6950,1850)","0","dev_discrete","I68";
;
CDS_SEC"1"
CDS_LOCATION"C5G90"
VOLTAGE"4V"
LOCATION"C5G90"
VALUE"22.0UF"
MATERIAL"X6S"
PACK_TYPE"0603V"
TOLERANCE"20%"
PART_NUMBER"E15431-004"
GROUP"PWR_MLCC_CAP"
BOM_DS"NOPOP"
ROOM"PVDDQ_KLM"
CDS_LIB"dev_discrete"
SEC"1"
SEC_TYPE"0603V";
"B"
$PN"2"1;
"A"
$PN"1"6;
%"CAP_A"
"1","(-7350,1850)","0","dev_discrete","I69";
;
CDS_SEC"1"
CDS_LOCATION"C5G89"
VOLTAGE"4V"
VALUE"22.0UF"
MATERIAL"X6S"
LOCATION"C5G89"
TOLERANCE"20%"
PACK_TYPE"0603V"
PART_NUMBER"E15431-004"
GROUP"PWR_MLCC_CAP"
BOM_DS"NOPOP"
SEC_TYPE"0603V"
SEC"1"
ROOM"PVDDQ_KLM"
CDS_LIB"dev_discrete";
"B"
$PN"2"1;
"A"
$PN"1"6;
%"CAP_A"
"1","(-7750,1850)","0","dev_discrete","I70";
;
CDS_SEC"1"
CDS_LOCATION"C5G88"
TOLERANCE"20%"
MATERIAL"X6S"
PACK_TYPE"0603V"
VOLTAGE"4V"
PART_NUMBER"E15431-004"
LOCATION"C5G88"
VALUE"22.0UF"
GROUP"PWR_MLCC_CAP"
BOM_DS"NOPOP"
SEC_TYPE"0603V"
SEC"1"
ROOM"PVDDQ_KLM"
CDS_LIB"dev_discrete";
"B"
$PN"2"1;
"A"
$PN"1"6;
%"CAP_A"
"1","(-1400,2800)","0","dev_discrete","I71";
;
CDS_SEC"1"
CDS_LOCATION"C5G103"
BOM_DS"NOPOP"
PART_NUMBER"E15431-004"
PACK_TYPE"0603V"
VOLTAGE"4V"
VALUE"22.0UF"
LOCATION"C5G103"
MATERIAL"X6S"
TOLERANCE"20%"
GROUP"PWR_MLCC_CAP"
SEC_TYPE"0603V"
SEC"1"
ROOM"PVDDQ_KLM"
CDS_LIB"dev_discrete";
"B"
$PN"2"7;
"A"
$PN"1"8;
%"CAP_A"
"1","(-1000,2800)","0","dev_discrete","I72";
;
CDS_SEC"1"
CDS_LOCATION"C5G104"
PART_NUMBER"E15431-004"
LOCATION"C5G104"
VALUE"22.0UF"
VOLTAGE"4V"
MATERIAL"X6S"
PACK_TYPE"0603V"
TOLERANCE"20%"
GROUP"PWR_MLCC_CAP"
BOM_DS"NOPOP"
CDS_LIB"dev_discrete"
ROOM"PVDDQ_KLM"
SEC"1"
SEC_TYPE"0603V";
"B"
$PN"2"7;
"A"
$PN"1"8;
%"CAP_A"
"1","(-600,2800)","0","dev_discrete","I73";
;
CDS_SEC"1"
CDS_LOCATION"C5G105"
PART_NUMBER"E15431-004"
VALUE"22.0UF"
TOLERANCE"20%"
LOCATION"C5G105"
MATERIAL"X6S"
VOLTAGE"4V"
PACK_TYPE"0603V"
GROUP"PWR_MLCC_CAP"
BOM_DS"NOPOP"
CDS_LIB"dev_discrete"
ROOM"PVDDQ_KLM"
SEC"1"
SEC_TYPE"0603V";
"B"
$PN"2"7;
"A"
$PN"1"8;
%"CAP_A"
"1","(-1800,2800)","0","dev_discrete","I74";
;
CDS_SEC"1"
CDS_LOCATION"C5G102"
GROUP"PWR_MLCC_CAP"
VALUE"22.0UF"
MATERIAL"X6S"
LOCATION"C5G102"
PACK_TYPE"0603V"
PART_NUMBER"E15431-004"
VOLTAGE"4V"
TOLERANCE"20%"
BOM_DS"NOPOP"
CDS_LIB"dev_discrete"
ROOM"PVDDQ_KLM"
SEC"1"
SEC_TYPE"0603V";
"B"
$PN"2"7;
"A"
$PN"1"8;
%"CAP_A"
"1","(-2200,2800)","0","dev_discrete","I75";
;
CDS_SEC"1"
CDS_LOCATION"C5G101"
PACK_TYPE"0603V"
MATERIAL"X6S"
LOCATION"C5G101"
PART_NUMBER"E15431-004"
TOLERANCE"20%"
VOLTAGE"4V"
VALUE"22.0UF"
GROUP"PWR_MLCC_CAP"
BOM_DS"NOPOP"
SEC_TYPE"0603V"
SEC"1"
ROOM"PVDDQ_KLM"
CDS_LIB"dev_discrete";
"B"
$PN"2"7;
"A"
$PN"1"8;
%"CAP_A"
"1","(-2600,2800)","0","dev_discrete","I76";
;
CDS_SEC"1"
CDS_LOCATION"C5G100"
PART_NUMBER"E15431-004"
MATERIAL"X6S"
LOCATION"C5G100"
VALUE"22.0UF"
TOLERANCE"20%"
VOLTAGE"4V"
PACK_TYPE"0603V"
GROUP"PWR_MLCC_CAP"
BOM_DS"NOPOP"
SEC_TYPE"0603V"
SEC"1"
ROOM"PVDDQ_KLM"
CDS_LIB"dev_discrete";
"B"
$PN"2"7;
"A"
$PN"1"8;
%"CAP_A"
"1","(-3000,2800)","0","dev_discrete","I77";
;
CDS_SEC"1"
CDS_LOCATION"C5G99"
TOLERANCE"20%"
MATERIAL"X6S"
VOLTAGE"4V"
LOCATION"C5G99"
VALUE"22.0UF"
PART_NUMBER"E15431-004"
PACK_TYPE"0603V"
GROUP"PWR_MLCC_CAP"
BOM_DS"NOPOP"
SEC_TYPE"0603V"
SEC"1"
ROOM"PVDDQ_KLM"
CDS_LIB"dev_discrete";
"B"
$PN"2"7;
"A"
$PN"1"8;
%"CAP_A"
"1","(-3400,2800)","0","dev_discrete","I78";
;
CDS_SEC"1"
CDS_LOCATION"C5G98"
MATERIAL"X6S"
VALUE"22.0UF"
LOCATION"C5G98"
PACK_TYPE"0603V"
VOLTAGE"4V"
PART_NUMBER"E15431-004"
TOLERANCE"20%"
GROUP"PWR_MLCC_CAP"
BOM_DS"NOPOP"
CDS_LIB"dev_discrete"
ROOM"PVDDQ_KLM"
SEC"1"
SEC_TYPE"0603V";
"B"
$PN"2"7;
"A"
$PN"1"8;
%"CAP_A"
"1","(-3800,2800)","0","dev_discrete","I79";
;
CDS_SEC"1"
CDS_LOCATION"C5G97"
PACK_TYPE"0603V"
VALUE"22.0UF"
LOCATION"C5G97"
MATERIAL"X6S"
TOLERANCE"20%"
VOLTAGE"4V"
PART_NUMBER"E15431-004"
GROUP"PWR_MLCC_CAP"
BOM_DS"NOPOP"
SEC_TYPE"0603V"
SEC"1"
ROOM"PVDDQ_KLM"
CDS_LIB"dev_discrete";
"B"
$PN"2"7;
"A"
$PN"1"8;
%"PVDDQ_GHJ"
"1","(-7750,3100)","0","mstr_symbols","I8";
;
HDL_POWER"PVDDQ_GHJ"
BODY_TYPE"PLUMBING"
CDS_LIB"mstr_symbols"
VOLTAGE"1.2V";
"G\NAC"12;
%"CAP_A"
"1","(-600,1850)","0","dev_discrete","I80";
;
CDS_SEC"1"
CDS_LOCATION"C5G114"
BOM_DS"NOPOP"
GROUP"PWR_MLCC_CAP"
VOLTAGE"4V"
VALUE"22.0UF"
LOCATION"C5G114"
PART_NUMBER"E15431-004"
TOLERANCE"20%"
PACK_TYPE"0603V"
MATERIAL"X6S"
ROOM"PVDDQ_KLM"
CDS_LIB"dev_discrete"
SEC"1"
SEC_TYPE"0603V";
"B"
$PN"2"4;
"A"
$PN"1"5;
%"CAP_A"
"1","(-1000,1850)","0","dev_discrete","I81";
;
CDS_SEC"1"
CDS_LOCATION"C5G113"
BOM_DS"NOPOP"
MATERIAL"X6S"
PART_NUMBER"E15431-004"
GROUP"PWR_MLCC_CAP"
PACK_TYPE"0603V"
TOLERANCE"20%"
LOCATION"C5G113"
VALUE"22.0UF"
VOLTAGE"4V"
SEC_TYPE"0603V"
SEC"1"
CDS_LIB"dev_discrete"
ROOM"PVDDQ_KLM";
"B"
$PN"2"4;
"A"
$PN"1"5;
%"CAP_A"
"1","(-1400,1850)","0","dev_discrete","I82";
;
CDS_SEC"1"
CDS_LOCATION"C5G112"
BOM_DS"NOPOP"
LOCATION"C5G112"
TOLERANCE"20%"
VOLTAGE"4V"
MATERIAL"X6S"
VALUE"22.0UF"
PART_NUMBER"E15431-004"
PACK_TYPE"0603V"
GROUP"PWR_MLCC_CAP"
ROOM"PVDDQ_KLM"
CDS_LIB"dev_discrete"
SEC"1"
SEC_TYPE"0603V";
"B"
$PN"2"4;
"A"
$PN"1"5;
%"CAP_A"
"1","(-1800,1850)","0","dev_discrete","I83";
;
CDS_SEC"1"
CDS_LOCATION"C5G111"
BOM_DS"NOPOP"
TOLERANCE"20%"
VOLTAGE"4V"
LOCATION"C5G111"
VALUE"22.0UF"
MATERIAL"X6S"
PART_NUMBER"E15431-004"
PACK_TYPE"0603V"
GROUP"PWR_MLCC_CAP"
SEC_TYPE"0603V"
SEC"1"
CDS_LIB"dev_discrete"
ROOM"PVDDQ_KLM";
"B"
$PN"2"4;
"A"
$PN"1"5;
%"CAP_A"
"1","(-2200,1850)","0","dev_discrete","I84";
;
CDS_SEC"1"
CDS_LOCATION"C5G110"
BOM_DS"NOPOP"
TOLERANCE"20%"
VOLTAGE"4V"
LOCATION"C5G110"
VALUE"22.0UF"
MATERIAL"X6S"
PACK_TYPE"0603V"
PART_NUMBER"E15431-004"
GROUP"PWR_MLCC_CAP"
ROOM"PVDDQ_KLM"
CDS_LIB"dev_discrete"
SEC"1"
SEC_TYPE"0603V";
"B"
$PN"2"4;
"A"
$PN"1"5;
%"CAP_A"
"1","(-2600,1850)","0","dev_discrete","I85";
;
CDS_SEC"1"
CDS_LOCATION"C5G109"
BOM_DS"NOPOP"
VOLTAGE"4V"
PACK_TYPE"0603V"
PART_NUMBER"E15431-004"
TOLERANCE"20%"
MATERIAL"X6S"
LOCATION"C5G109"
VALUE"22.0UF"
GROUP"PWR_MLCC_CAP"
SEC_TYPE"0603V"
SEC"1"
CDS_LIB"dev_discrete"
ROOM"PVDDQ_KLM";
"B"
$PN"2"4;
"A"
$PN"1"5;
%"CAP_A"
"1","(-3000,1850)","0","dev_discrete","I86";
;
CDS_SEC"1"
CDS_LOCATION"C5G108"
BOM_DS"NOPOP"
LOCATION"C5G108"
PACK_TYPE"0603V"
TOLERANCE"20%"
VOLTAGE"4V"
VALUE"22.0UF"
MATERIAL"X6S"
PART_NUMBER"E15431-004"
GROUP"PWR_MLCC_CAP"
ROOM"PVDDQ_KLM"
CDS_LIB"dev_discrete"
SEC"1"
SEC_TYPE"0603V";
"B"
$PN"2"4;
"A"
$PN"1"5;
%"CAP_A"
"1","(-3400,1850)","0","dev_discrete","I87";
;
CDS_SEC"1"
CDS_LOCATION"C5G107"
BOM_DS"NOPOP"
VOLTAGE"4V"
VALUE"22.0UF"
PACK_TYPE"0603V"
LOCATION"C5G107"
TOLERANCE"20%"
MATERIAL"X6S"
PART_NUMBER"E15431-004"
GROUP"PWR_MLCC_CAP"
SEC_TYPE"0603V"
SEC"1"
CDS_LIB"dev_discrete"
ROOM"PVDDQ_KLM";
"B"
$PN"2"4;
"A"
$PN"1"5;
%"CAP_A"
"1","(-3800,1850)","0","dev_discrete","I88";
;
CDS_SEC"1"
CDS_LOCATION"C5G106"
BOM_DS"NOPOP"
PART_NUMBER"E15431-004"
LOCATION"C5G106"
TOLERANCE"20%"
PACK_TYPE"0603V"
VALUE"22.0UF"
VOLTAGE"4V"
MATERIAL"X6S"
GROUP"PWR_MLCC_CAP"
ROOM"PVDDQ_KLM"
CDS_LIB"dev_discrete"
SEC"1"
SEC_TYPE"0603V";
"B"
$PN"2"4;
"A"
$PN"1"5;
%"CAP"
"1","(-3800,3775)","0","mstr_discrete","I89";
;
CDS_SEC"1"
CDS_LOCATION"C5G115"
GROUP"PWR_MLCC_CAP"
PART_NUMBER"C95333-006"
PACK_TYPE"0805"
MATERIAL"X6S"
TOLERANCE"20%"
LOCATION"C5G115"
VALUE"47UF"
VOLTAGE"4V"
POP"NOPOP"
CDS_LIB"mstr_discrete"
ROOM"PVCCIN_CPU0_DECAP_VR"
BOM_COST"PROC_SOCKET"
SEC"1"
SEC_TYPE"0805";
"A"
$PN"1"10;
"B"
$PN"2"9;
%"CAP"
"1","(-3400,3775)","0","mstr_discrete","I90";
;
CDS_SEC"1"
CDS_LOCATION"C5G116"
LOCATION"C5G116"
VALUE"47UF"
VOLTAGE"4V"
PART_NUMBER"C95333-006"
GROUP"PWR_MLCC_CAP"
POP"NOPOP"
PACK_TYPE"0805"
MATERIAL"X6S"
TOLERANCE"20%"
ROOM"PVCCIN_CPU0_DECAP_VR"
BOM_COST"PROC_SOCKET"
CDS_LIB"mstr_discrete"
SEC"1"
SEC_TYPE"0805";
"A"
$PN"1"10;
"B"
$PN"2"9;
%"CAP"
"1","(-7350,3750)","0","mstr_discrete","I91";
;
CDS_SEC"1"
CDS_LOCATION"C5G118"
VOLTAGE"4V"
VALUE"47UF"
LOCATION"C5G118"
MATERIAL"X6S"
TOLERANCE"20%"
POP"NOPOP"
PART_NUMBER"C95333-006"
PACK_TYPE"0805"
GROUP"PWR_MLCC_CAP"
CDS_LIB"mstr_discrete"
ROOM"PVCCIN_CPU0_DECAP_VR"
BOM_COST"PROC_SOCKET"
SEC"1"
SEC_TYPE"0805";
"A"
$PN"1"3;
"B"
$PN"2"2;
%"CAP"
"1","(-7750,3750)","0","mstr_discrete","I92";
;
CDS_SEC"1"
CDS_LOCATION"C5G117"
POP"NOPOP"
VOLTAGE"4V"
VALUE"47UF"
TOLERANCE"20%"
MATERIAL"X6S"
PACK_TYPE"0805"
PART_NUMBER"C95333-006"
GROUP"PWR_MLCC_CAP"
LOCATION"C5G117"
ROOM"PVCCIN_CPU0_DECAP_VR"
BOM_COST"PROC_SOCKET"
CDS_LIB"mstr_discrete"
SEC"1"
SEC_TYPE"0805";
"A"
$PN"1"3;
"B"
$PN"2"2;
END.
